FILE_TYPE = MACRO_DRAWING;
SET COLOR_WIRE YELLOW;
SET COLOR_PROP MONO;
SET COLOR_DOT WHITE;
SET COLOR_ARC YELLOW;
SET COLOR_BODY GREEN;
SET COLOR_NOTE MONO;
SET PROP_DISPLAY VALUE;
SET PAGE_NUMBER P36;
FORCEADD VCC_CORE..1
(-4500 3800);
FORCEPROP 3 LASTPIN (-4500 3750) SIG_NAME PVCCMCP_CPU0\g
J 0
(-4490 3760);
DISPLAY 0.659574 (-4490 3760);
PAINT MONO (-4490 3760);
DISPLAY INVISIBLE (-4490 3760);
FORCEPROP 1 LAST HDL_POWER PVCCMCP_CPU0
J 1
(-4500 3850);
DISPLAY 0.617021 (-4500 3850);
PAINT GREEN (-4500 3850);
FORCEPROP 2 LAST CDS_LIB mstr_symbols
J 0
(-4500 3800);
PAINT ORANGE (-4500 3800);
DISPLAY INVISIBLE (-4500 3800);
FORCEPROP 1 LAST PATH I12
J 0
(-4450 3825);
DISPLAY 0.872340 (-4450 3825);
PAINT AQUA (-4450 3825);
DISPLAY INVISIBLE (-4450 3825);
FORCEADD VCC_CORE..1
(-925 2700);
FORCEPROP 3 LASTPIN (-925 2650) SIG_NAME PVCCMCP_CPU0\g
J 0
(-915 2660);
DISPLAY 0.659574 (-915 2660);
PAINT MONO (-915 2660);
DISPLAY INVISIBLE (-915 2660);
FORCEPROP 1 LAST HDL_POWER PVCCMCP_CPU0
J 1
(-925 2750);
DISPLAY 0.617021 (-925 2750);
PAINT GREEN (-925 2750);
FORCEPROP 2 LAST CDS_LIB mstr_symbols
J 0
(-925 2700);
PAINT ORANGE (-925 2700);
DISPLAY INVISIBLE (-925 2700);
FORCEPROP 1 LAST PATH I13
J 0
(-875 2725);
DISPLAY 0.872340 (-875 2725);
PAINT AQUA (-875 2725);
DISPLAY INVISIBLE (-875 2725);
FORCEADD VCC_CORE..1
(-7850 2350);
FORCEPROP 3 LASTPIN (-7850 2300) SIG_NAME PVCCMCP_CPU0\g
J 0
(-7840 2310);
DISPLAY 0.659574 (-7840 2310);
PAINT MONO (-7840 2310);
DISPLAY INVISIBLE (-7840 2310);
FORCEPROP 1 LAST HDL_POWER PVCCMCP_CPU0
J 1
(-7850 2400);
DISPLAY 0.617021 (-7850 2400);
PAINT GREEN (-7850 2400);
FORCEPROP 2 LAST CDS_LIB mstr_symbols
J 0
(-7850 2350);
PAINT ORANGE (-7850 2350);
DISPLAY INVISIBLE (-7850 2350);
FORCEPROP 1 LAST PATH I14
J 0
(-7800 2375);
DISPLAY 0.872340 (-7800 2375);
PAINT AQUA (-7800 2375);
DISPLAY INVISIBLE (-7800 2375);
FORCEADD SKX_EXT_B..16
(-6075 2550);
FORCEPROP 2 LASTPIN (-6675 1550) $PN BU18
J 2
(-6685 1560);
DISPLAY 0.617021 (-6685 1560);
PAINT ORANGE (-6685 1560);
FORCEPROP 2 LASTPIN (-6675 1500) $PN BU20
J 2
(-6685 1510);
DISPLAY 0.617021 (-6685 1510);
PAINT ORANGE (-6685 1510);
FORCEPROP 2 LASTPIN (-6675 1600) $PN BR24
J 2
(-6685 1610);
DISPLAY 0.617021 (-6685 1610);
PAINT ORANGE (-6685 1610);
FORCEPROP 2 LASTPIN (-6675 1650) $PN BR22
J 2
(-6685 1660);
DISPLAY 0.617021 (-6685 1660);
PAINT ORANGE (-6685 1660);
FORCEPROP 2 LASTPIN (-6675 1750) $PN BP17
J 2
(-6685 1760);
DISPLAY 0.617021 (-6685 1760);
PAINT ORANGE (-6685 1760);
FORCEPROP 2 LASTPIN (-6675 1800) $PN BN18
J 2
(-6685 1810);
DISPLAY 0.617021 (-6685 1810);
PAINT ORANGE (-6685 1810);
FORCEPROP 2 LASTPIN (-6675 1850) $PN BM19
J 2
(-6685 1860);
DISPLAY 0.617021 (-6685 1860);
PAINT ORANGE (-6685 1860);
FORCEPROP 2 LASTPIN (-6675 1900) $PN BM17
J 2
(-6685 1910);
DISPLAY 0.617021 (-6685 1910);
PAINT ORANGE (-6685 1910);
FORCEPROP 2 LASTPIN (-6675 2750) $PN BD25
J 2
(-6685 2760);
DISPLAY 0.617021 (-6685 2760);
PAINT ORANGE (-6685 2760);
FORCEPROP 2 LASTPIN (-6675 2700) $PN BD65
J 2
(-6685 2710);
DISPLAY 0.617021 (-6685 2710);
PAINT ORANGE (-6685 2710);
FORCEPROP 2 LASTPIN (-6675 2650) $PN BD67
J 2
(-6685 2660);
DISPLAY 0.617021 (-6685 2660);
PAINT ORANGE (-6685 2660);
FORCEPROP 2 LASTPIN (-6675 2600) $PN BD69
J 2
(-6685 2610);
DISPLAY 0.617021 (-6685 2610);
PAINT ORANGE (-6685 2610);
FORCEPROP 2 LASTPIN (-6675 2550) $PN BE18
J 2
(-6685 2560);
DISPLAY 0.617021 (-6685 2560);
PAINT ORANGE (-6685 2560);
FORCEPROP 2 LASTPIN (-6675 1950) $PN BL20
J 2
(-6685 1960);
DISPLAY 0.617021 (-6685 1960);
PAINT ORANGE (-6685 1960);
FORCEPROP 2 LASTPIN (-6675 2000) $PN BL18
J 2
(-6685 2010);
DISPLAY 0.617021 (-6685 2010);
PAINT ORANGE (-6685 2010);
FORCEPROP 2 LASTPIN (-6675 2050) $PN BK17
J 2
(-6685 2060);
DISPLAY 0.617021 (-6685 2060);
PAINT ORANGE (-6685 2060);
FORCEPROP 2 LASTPIN (-6675 2300) $PN BG20
J 2
(-6685 2310);
DISPLAY 0.617021 (-6685 2310);
PAINT ORANGE (-6685 2310);
FORCEPROP 2 LASTPIN (-6675 2250) $PN BH19
J 2
(-6685 2260);
DISPLAY 0.617021 (-6685 2260);
PAINT ORANGE (-6685 2260);
FORCEPROP 2 LASTPIN (-6675 2200) $PN BJ16
J 2
(-6685 2210);
DISPLAY 0.617021 (-6685 2210);
PAINT ORANGE (-6685 2210);
FORCEPROP 2 LASTPIN (-6675 2150) $PN BJ18
J 2
(-6685 2160);
DISPLAY 0.617021 (-6685 2160);
PAINT ORANGE (-6685 2160);
FORCEPROP 2 LASTPIN (-6675 1700) $PN BP21
J 2
(-6685 1710);
DISPLAY 0.617021 (-6685 1710);
PAINT ORANGE (-6685 1710);
FORCEPROP 2 LASTPIN (-6675 2450) $PN BE22
J 2
(-6685 2460);
DISPLAY 0.617021 (-6685 2460);
PAINT ORANGE (-6685 2460);
FORCEPROP 1 LAST LOCATION U5D1
J 0
(-6625 3900);
DISPLAY 0.617021 (-6625 3900);
PAINT AQUA (-6625 3900);
FORCEPROP 1 LAST PART_NUMBER TBD
J 0
(-6625 1250);
DISPLAY 0.617021 (-6625 1250);
PAINT BLUE (-6625 1250);
FORCEPROP 1 LAST MATERIAL IC
J 0
(-6625 3850);
DISPLAY 0.617021 (-6625 3850);
PAINT SKYBLUE (-6625 3850);
FORCEPROP 2 LASTPIN (-5475 1900) $PN AY83
J 0
(-5465 1910);
DISPLAY 0.617021 (-5465 1910);
PAINT ORANGE (-5465 1910);
FORCEPROP 2 LASTPIN (-6675 3650) $PN BA78
J 2
(-6685 3660);
DISPLAY 0.617021 (-6685 3660);
PAINT ORANGE (-6685 3660);
FORCEPROP 2 LASTPIN (-6675 3600) $PN BA82
J 2
(-6685 3610);
DISPLAY 0.617021 (-6685 3610);
PAINT ORANGE (-6685 3610);
FORCEPROP 2 LASTPIN (-6675 3550) $PN BB13
J 2
(-6685 3560);
DISPLAY 0.617021 (-6685 3560);
PAINT ORANGE (-6685 3560);
FORCEPROP 2 LASTPIN (-6675 3500) $PN BB15
J 2
(-6685 3510);
DISPLAY 0.617021 (-6685 3510);
PAINT ORANGE (-6685 3510);
FORCEPROP 2 LASTPIN (-6675 3450) $PN BB17
J 2
(-6685 3460);
DISPLAY 0.617021 (-6685 3460);
PAINT ORANGE (-6685 3460);
FORCEPROP 2 LASTPIN (-6675 3400) $PN BB21
J 2
(-6685 3410);
DISPLAY 0.617021 (-6685 3410);
PAINT ORANGE (-6685 3410);
FORCEPROP 2 LASTPIN (-6675 3350) $PN BB25
J 2
(-6685 3360);
DISPLAY 0.617021 (-6685 3360);
PAINT ORANGE (-6685 3360);
FORCEPROP 2 LASTPIN (-6675 3300) $PN BB65
J 2
(-6685 3310);
DISPLAY 0.617021 (-6685 3310);
PAINT ORANGE (-6685 3310);
FORCEPROP 2 LASTPIN (-6675 3250) $PN BB67
J 2
(-6685 3260);
DISPLAY 0.617021 (-6685 3260);
PAINT ORANGE (-6685 3260);
FORCEPROP 2 LASTPIN (-6675 3200) $PN BC14
J 2
(-6685 3210);
DISPLAY 0.617021 (-6685 3210);
PAINT ORANGE (-6685 3210);
FORCEPROP 2 LASTPIN (-6675 3150) $PN BC18
J 2
(-6685 3160);
DISPLAY 0.617021 (-6685 3160);
PAINT ORANGE (-6685 3160);
FORCEPROP 2 LASTPIN (-6675 3100) $PN BC20
J 2
(-6685 3110);
DISPLAY 0.617021 (-6685 3110);
PAINT ORANGE (-6685 3110);
FORCEPROP 2 LASTPIN (-6675 3050) $PN BC22
J 2
(-6685 3060);
DISPLAY 0.617021 (-6685 3060);
PAINT ORANGE (-6685 3060);
FORCEPROP 2 LASTPIN (-6675 3000) $PN BC64
J 2
(-6685 3010);
DISPLAY 0.617021 (-6685 3010);
PAINT ORANGE (-6685 3010);
FORCEPROP 2 LASTPIN (-6675 2950) $PN BC66
J 2
(-6685 2960);
DISPLAY 0.617021 (-6685 2960);
PAINT ORANGE (-6685 2960);
FORCEPROP 2 LASTPIN (-6675 2900) $PN BC68
J 2
(-6685 2910);
DISPLAY 0.617021 (-6685 2910);
PAINT ORANGE (-6685 2910);
FORCEPROP 2 LASTPIN (-6675 2850) $PN BD17
J 2
(-6685 2860);
DISPLAY 0.617021 (-6685 2860);
PAINT ORANGE (-6685 2860);
FORCEPROP 2 LASTPIN (-6675 2800) $PN BD19
J 2
(-6685 2810);
DISPLAY 0.617021 (-6685 2810);
PAINT ORANGE (-6685 2810);
FORCEPROP 2 LASTPIN (-6675 2500) $PN BE20
J 2
(-6685 2510);
DISPLAY 0.617021 (-6685 2510);
PAINT ORANGE (-6685 2510);
FORCEPROP 2 LASTPIN (-6675 2400) $PN BF21
J 2
(-6685 2410);
DISPLAY 0.617021 (-6685 2410);
PAINT ORANGE (-6685 2410);
FORCEPROP 2 LASTPIN (-6675 2350) $PN BG18
J 2
(-6685 2360);
DISPLAY 0.617021 (-6685 2360);
PAINT ORANGE (-6685 2360);
FORCEPROP 2 LASTPIN (-6675 2100) $PN BJ20
J 2
(-6685 2110);
DISPLAY 0.617021 (-6685 2110);
PAINT ORANGE (-6685 2110);
FORCEPROP 2 LASTPIN (-6675 1450) $PN BU22
J 2
(-6685 1460);
DISPLAY 0.617021 (-6685 1460);
PAINT ORANGE (-6685 1460);
FORCEPROP 2 LASTPIN (-5475 3650) $PN BV19
J 0
(-5465 3660);
DISPLAY 0.617021 (-5465 3660);
PAINT ORANGE (-5465 3660);
FORCEPROP 2 LASTPIN (-5475 3600) $PN BV21
J 0
(-5465 3610);
DISPLAY 0.617021 (-5465 3610);
PAINT ORANGE (-5465 3610);
FORCEPROP 2 LASTPIN (-5475 3550) $PN BV23
J 0
(-5465 3560);
DISPLAY 0.617021 (-5465 3560);
PAINT ORANGE (-5465 3560);
FORCEPROP 2 LASTPIN (-5475 3500) $PN BW10
J 0
(-5465 3510);
DISPLAY 0.617021 (-5465 3510);
PAINT ORANGE (-5465 3510);
FORCEPROP 2 LASTPIN (-5475 3450) $PN BW20
J 0
(-5465 3460);
DISPLAY 0.617021 (-5465 3460);
PAINT ORANGE (-5465 3460);
FORCEPROP 2 LASTPIN (-5475 3400) $PN BW22
J 0
(-5465 3410);
DISPLAY 0.617021 (-5465 3410);
PAINT ORANGE (-5465 3410);
FORCEPROP 2 LASTPIN (-5475 3350) $PN BY19
J 0
(-5465 3360);
DISPLAY 0.617021 (-5465 3360);
PAINT ORANGE (-5465 3360);
FORCEPROP 2 LASTPIN (-5475 3300) $PN BY25
J 0
(-5465 3310);
DISPLAY 0.617021 (-5465 3310);
PAINT ORANGE (-5465 3310);
FORCEPROP 2 LASTPIN (-5475 3250) $PN CA22
J 0
(-5465 3260);
DISPLAY 0.617021 (-5465 3260);
PAINT ORANGE (-5465 3260);
FORCEPROP 2 LASTPIN (-5475 3200) $PN CA24
J 0
(-5465 3210);
DISPLAY 0.617021 (-5465 3210);
PAINT ORANGE (-5465 3210);
FORCEPROP 2 LASTPIN (-5475 3150) $PN CB19
J 0
(-5465 3160);
DISPLAY 0.617021 (-5465 3160);
PAINT ORANGE (-5465 3160);
FORCEPROP 2 LASTPIN (-5475 3100) $PN CB21
J 0
(-5465 3110);
DISPLAY 0.617021 (-5465 3110);
PAINT ORANGE (-5465 3110);
FORCEPROP 2 LASTPIN (-5475 3000) $PN CB5
J 0
(-5465 3010);
DISPLAY 0.617021 (-5465 3010);
PAINT ORANGE (-5465 3010);
FORCEPROP 2 LASTPIN (-5475 2900) $PN CC6
J 0
(-5465 2910);
DISPLAY 0.617021 (-5465 2910);
PAINT ORANGE (-5465 2910);
FORCEPROP 2 LASTPIN (-5475 2850) $PN CD19
J 0
(-5465 2860);
DISPLAY 0.617021 (-5465 2860);
PAINT ORANGE (-5465 2860);
FORCEPROP 2 LASTPIN (-5475 2800) $PN CD21
J 0
(-5465 2810);
DISPLAY 0.617021 (-5465 2810);
PAINT ORANGE (-5465 2810);
FORCEPROP 2 LASTPIN (-5475 2750) $PN CD25
J 0
(-5465 2760);
DISPLAY 0.617021 (-5465 2760);
PAINT ORANGE (-5465 2760);
FORCEPROP 2 LASTPIN (-5475 2700) $PN CE22
J 0
(-5465 2710);
DISPLAY 0.617021 (-5465 2710);
PAINT ORANGE (-5465 2710);
FORCEPROP 2 LASTPIN (-5475 2650) $PN CE78
J 0
(-5465 2660);
DISPLAY 0.617021 (-5465 2660);
PAINT ORANGE (-5465 2660);
FORCEPROP 2 LASTPIN (-5475 2600) $PN CE80
J 0
(-5465 2610);
DISPLAY 0.617021 (-5465 2610);
PAINT ORANGE (-5465 2610);
FORCEPROP 2 LASTPIN (-5475 2550) $PN CF19
J 0
(-5465 2560);
DISPLAY 0.617021 (-5465 2560);
PAINT ORANGE (-5465 2560);
FORCEPROP 2 LASTPIN (-5475 2500) $PN CF21
J 0
(-5465 2510);
DISPLAY 0.617021 (-5465 2510);
PAINT ORANGE (-5465 2510);
FORCEPROP 2 LASTPIN (-5475 2450) $PN CF23
J 0
(-5465 2460);
DISPLAY 0.617021 (-5465 2460);
PAINT ORANGE (-5465 2460);
FORCEPROP 2 LASTPIN (-5475 2400) $PN CF79
J 0
(-5465 2410);
DISPLAY 0.617021 (-5465 2410);
PAINT ORANGE (-5465 2410);
FORCEPROP 2 LASTPIN (-5475 2350) $PN CF81
J 0
(-5465 2360);
DISPLAY 0.617021 (-5465 2360);
PAINT ORANGE (-5465 2360);
FORCEPROP 2 LASTPIN (-5475 2300) $PN CG10
J 0
(-5465 2310);
DISPLAY 0.617021 (-5465 2310);
PAINT ORANGE (-5465 2310);
FORCEPROP 2 LASTPIN (-5475 2250) $PN CG20
J 0
(-5465 2260);
DISPLAY 0.617021 (-5465 2260);
PAINT ORANGE (-5465 2260);
FORCEPROP 2 LASTPIN (-5475 2200) $PN CG24
J 0
(-5465 2210);
DISPLAY 0.617021 (-5465 2210);
PAINT ORANGE (-5465 2210);
FORCEPROP 2 LASTPIN (-5475 2150) $PN CG26
J 0
(-5465 2160);
DISPLAY 0.617021 (-5465 2160);
PAINT ORANGE (-5465 2160);
FORCEPROP 2 LASTPIN (-5475 2100) $PN CG78
J 0
(-5465 2110);
DISPLAY 0.617021 (-5465 2110);
PAINT ORANGE (-5465 2110);
FORCEPROP 2 LASTPIN (-5475 2050) $PN CG82
J 0
(-5465 2060);
DISPLAY 0.617021 (-5465 2060);
PAINT ORANGE (-5465 2060);
FORCEPROP 2 LASTPIN (-5475 2000) $PN CH21
J 0
(-5465 2010);
DISPLAY 0.617021 (-5465 2010);
PAINT ORANGE (-5465 2010);
FORCEPROP 2 LASTPIN (-5475 1950) $PN CH23
J 0
(-5465 1960);
DISPLAY 0.617021 (-5465 1960);
PAINT ORANGE (-5465 1960);
FORCEPROP 2 LASTPIN (-5475 3050) $PN CB25
J 0
(-5465 3060);
DISPLAY 0.617021 (-5465 3060);
PAINT ORANGE (-5465 3060);
FORCEPROP 2 LASTPIN (-5475 2950) $PN CC20
J 0
(-5465 2960);
DISPLAY 0.617021 (-5465 2960);
PAINT ORANGE (-5465 2960);
FORCEPROP 1 LAST PACK_TYPE BGA1
J 0
(-6625 3950);
PAINT SKYBLUE (-6625 3950);
DISPLAY INVISIBLE (-6625 3950);
FORCEPROP 2 LAST SEC_TYPE BGA1
J 0
(-6625 3950);
DISPLAY 1.021277 (-6625 3950);
PAINT ORANGE (-6625 3950);
DISPLAY INVISIBLE (-6625 3950);
FORCEPROP 2 LAST CDS_LIB chpset_lib
J 0
(-6075 2550);
PAINT ORANGE (-6075 2550);
DISPLAY INVISIBLE (-6075 2550);
FORCEPROP 2 LAST SEC 16
J 0
(-6625 3950);
DISPLAY 0.680851 (-6625 3950);
PAINT MONO (-6625 3950);
DISPLAY INVISIBLE (-6625 3950);
FORCEPROP 2 LAST CDS_LOCATION U5D1
J 0
(-6625 3900);
DISPLAY 0.617021 (-6625 3900);
PAINT AQUA (-6625 3900);
DISPLAY INVISIBLE (-6625 3900);
FORCEPROP 1 LAST PATH I15
J 0
(-6075 3850);
PAINT GREEN (-6075 3850);
DISPLAY INVISIBLE (-6075 3850);
FORCEPROP 0 LAST ROOM CPU0
J 0
(-6625 4000);
DISPLAY 1.021277 (-6625 4000);
PAINT ORANGE (-6625 4000);
DISPLAY INVISIBLE (-6625 4000);
FORCEADD SKX_EXT_B..17
(-2550 2525);
FORCEPROP 1 LAST LOCATION U5D1
J 0
(-3200 3275);
DISPLAY 0.617021 (-3200 3275);
PAINT AQUA (-3200 3275);
FORCEPROP 1 LAST PART_NUMBER TBD
J 0
(-3200 1975);
DISPLAY 0.617021 (-3200 1975);
PAINT BLUE (-3200 1975);
FORCEPROP 1 LAST MATERIAL IC
J 0
(-3200 3225);
DISPLAY 0.617021 (-3200 3225);
PAINT SKYBLUE (-3200 3225);
FORCEPROP 2 LASTPIN (-1850 2825) $PN AW22
J 0
(-1840 2835);
DISPLAY 0.617021 (-1840 2835);
PAINT ORANGE (-1840 2835);
FORCEPROP 2 LASTPIN (-1850 2875) $PN AW20
J 0
(-1840 2885);
DISPLAY 0.617021 (-1840 2885);
PAINT ORANGE (-1840 2885);
FORCEPROP 2 LASTPIN (-1850 2925) $PN AW16
J 0
(-1840 2935);
DISPLAY 0.617021 (-1840 2935);
PAINT ORANGE (-1840 2935);
FORCEPROP 2 LASTPIN (-1850 2975) $PN AU18
J 0
(-1840 2985);
DISPLAY 0.617021 (-1840 2985);
PAINT ORANGE (-1840 2985);
FORCEPROP 2 LASTPIN (-1850 3025) $PN AR16
J 0
(-1840 3035);
DISPLAY 0.617021 (-1840 3035);
PAINT ORANGE (-1840 3035);
FORCEPROP 2 LASTPIN (-1850 2725) $PN CH25
J 0
(-1840 2735);
DISPLAY 0.617021 (-1840 2735);
PAINT ORANGE (-1840 2735);
FORCEPROP 2 LASTPIN (-1850 2675) $PN CH77
J 0
(-1840 2685);
DISPLAY 0.617021 (-1840 2685);
PAINT ORANGE (-1840 2685);
FORCEPROP 2 LASTPIN (-1850 2575) $PN CJ20
J 0
(-1840 2585);
DISPLAY 0.617021 (-1840 2585);
PAINT ORANGE (-1840 2585);
FORCEPROP 2 LASTPIN (-1850 2525) $PN CJ22
J 0
(-1840 2535);
DISPLAY 0.617021 (-1840 2535);
PAINT ORANGE (-1840 2535);
FORCEPROP 2 LASTPIN (-1850 2475) $PN CJ24
J 0
(-1840 2485);
DISPLAY 0.617021 (-1840 2485);
PAINT ORANGE (-1840 2485);
FORCEPROP 2 LASTPIN (-1850 2425) $PN CJ26
J 0
(-1840 2435);
DISPLAY 0.617021 (-1840 2435);
PAINT ORANGE (-1840 2435);
FORCEPROP 2 LASTPIN (-1850 2375) $PN CK19
J 0
(-1840 2385);
DISPLAY 0.617021 (-1840 2385);
PAINT ORANGE (-1840 2385);
FORCEPROP 2 LASTPIN (-1850 2325) $PN CK23
J 0
(-1840 2335);
DISPLAY 0.617021 (-1840 2335);
PAINT ORANGE (-1840 2335);
FORCEPROP 2 LASTPIN (-1850 2275) $PN CK25
J 0
(-1840 2285);
DISPLAY 0.617021 (-1840 2285);
PAINT ORANGE (-1840 2285);
FORCEPROP 2 LASTPIN (-1850 2225) $PN CK77
J 0
(-1840 2235);
DISPLAY 0.617021 (-1840 2235);
PAINT ORANGE (-1840 2235);
FORCEPROP 2 LASTPIN (-1850 2175) $PN CL24
J 0
(-1840 2185);
DISPLAY 0.617021 (-1840 2185);
PAINT ORANGE (-1840 2185);
FORCEPROP 1 LAST PACK_TYPE BGA1
J 0
(-3200 3325);
PAINT SKYBLUE (-3200 3325);
DISPLAY INVISIBLE (-3200 3325);
FORCEPROP 2 LAST SEC_TYPE BGA1
J 0
(-3200 3325);
DISPLAY 1.021277 (-3200 3325);
PAINT ORANGE (-3200 3325);
DISPLAY INVISIBLE (-3200 3325);
FORCEPROP 2 LAST CDS_LIB chpset_lib
J 0
(-2550 2525);
PAINT ORANGE (-2550 2525);
DISPLAY INVISIBLE (-2550 2525);
FORCEPROP 2 LAST SEC 17
J 0
(-3200 3325);
DISPLAY 0.680851 (-3200 3325);
PAINT MONO (-3200 3325);
DISPLAY INVISIBLE (-3200 3325);
FORCEPROP 2 LAST CDS_LOCATION U5D1
J 0
(-3200 3275);
DISPLAY 0.617021 (-3200 3275);
PAINT AQUA (-3200 3275);
DISPLAY INVISIBLE (-3200 3275);
FORCEPROP 1 LAST PATH I16
J 0
(-2550 3225);
PAINT GREEN (-2550 3225);
DISPLAY INVISIBLE (-2550 3225);
FORCEPROP 0 LAST ROOM CPU0
J 0
(-3200 3375);
DISPLAY 1.021277 (-3200 3375);
PAINT ORANGE (-3200 3375);
DISPLAY INVISIBLE (-3200 3375);
FORCEADD VCC_CORE..1
(-7850 2100);
FORCEPROP 3 LASTPIN (-7850 2050) SIG_NAME PVCCIOMCP_CPU0\g
J 0
(-7840 2060);
DISPLAY 0.659574 (-7840 2060);
PAINT MONO (-7840 2060);
DISPLAY INVISIBLE (-7840 2060);
FORCEPROP 1 LAST HDL_POWER PVCCIOMCP_CPU0
J 1
(-7850 2150);
DISPLAY 0.617021 (-7850 2150);
PAINT GREEN (-7850 2150);
FORCEPROP 1 LAST PATH I17
J 0
(-7800 2125);
DISPLAY 0.872340 (-7800 2125);
PAINT AQUA (-7800 2125);
DISPLAY INVISIBLE (-7800 2125);
FORCEPROP 2 LAST CDS_LIB mstr_symbols
J 0
(-7850 2100);
PAINT ORANGE (-7850 2100);
DISPLAY INVISIBLE (-7850 2100);
FORCEADD OFFPAGE..1
(-7600 2750);
FORCEPROP 2 LAST $XR0 103 
J 0
(-7852 2750);
DISPLAY 0.638298 (-7852 2750);
PAINT MONO (-7852 2750);
FORCEPROP 2 LAST CDS_LIB mstr_standard
J 0
(-7600 2750);
PAINT MONO (-7600 2750);
DISPLAY INVISIBLE (-7600 2750);
FORCEPROP 1 LAST OFFPAGE TRUE
J 0
(-7275 2625);
DISPLAY 0.872340 (-7275 2625);
PAINT GREEN (-7275 2625);
DISPLAY INVISIBLE (-7275 2625);
FORCEPROP 1 LAST COMMENT_BODY TRUE
J 0
(-7475 2650);
DISPLAY 0.872340 (-7475 2650);
PAINT GREEN (-7475 2650);
DISPLAY INVISIBLE (-7475 2650);
FORCEPROP 2 LAST PATH I5
J 0
(-7550 2825);
DISPLAY 1.021277 (-7550 2825);
PAINT ORANGE (-7550 2825);
DISPLAY INVISIBLE (-7550 2825);
FORCEADD OFFPAGE..1
(-7600 3350);
FORCEPROP 2 LAST $XR0 103 
J 0
(-7852 3350);
DISPLAY 0.638298 (-7852 3350);
PAINT MONO (-7852 3350);
FORCEPROP 2 LAST CDS_LIB mstr_standard
J 0
(-7600 3350);
PAINT MONO (-7600 3350);
DISPLAY INVISIBLE (-7600 3350);
FORCEPROP 1 LAST OFFPAGE TRUE
J 0
(-7275 3225);
DISPLAY 0.872340 (-7275 3225);
PAINT GREEN (-7275 3225);
DISPLAY INVISIBLE (-7275 3225);
FORCEPROP 1 LAST COMMENT_BODY TRUE
J 0
(-7475 3250);
DISPLAY 0.872340 (-7475 3250);
PAINT GREEN (-7475 3250);
DISPLAY INVISIBLE (-7475 3250);
FORCEPROP 2 LAST PATH I8
J 0
(-7850 3400);
DISPLAY 1.021277 (-7850 3400);
PAINT ORANGE (-7850 3400);
DISPLAY INVISIBLE (-7850 3400);
FORCEADD DESIGN_NOTE..1
(-3000 1825);
FORCEPROP 0 LAST L1 CPU SYMBOLS 1-30 ARE PRELIMINARY AND SUBJECT TO CHANGE
J 0
(-3200 1700);
DISPLAY 1.021277 (-3200 1700);
PAINT ORANGE (-3200 1700);
FORCEPROP 2 LAST CDS_LIB mstr_symbols
J 0
(-3000 1825);
PAINT ORANGE (-3000 1825);
DISPLAY INVISIBLE (-3000 1825);
FORCEPROP 1 LAST COMMENT_BODY TRUE
J 0
(-2975 1925);
DISPLAY 0.978723 (-2975 1925);
PAINT ORANGE (-2975 1925);
DISPLAY INVISIBLE (-2975 1925);
FORCEADD INTEL_CORP_BPAGE..1
(-425 -50);
FORCEPROP 1 LAST CDS_CON_LAST_MODIFIED Fri Jun 16 17:48:13 2017
J 0
(-1850 275);
DISPLAY 1.340426 (-1850 275);
PAINT GREEN (-1850 275);
DISPLAY INVISIBLE (-1850 275);
FORCEPROP 1 LAST CUSTOM_TXT_CDS <CURRENT_DESIGN_SHEET> OF <TOTAL_DESIGN_SHEETS>
J 0
(-925 -25);
PAINT ORANGE (-925 -25);
FORCEPROP 1 LAST CUSTOM_TXT_CDS <CON_LAST_MODIFIED>
J 0
(-4425 50);
PAINT ORANGE (-4425 50);
FORCEPROP 2 LAST CUSTOM_TXT_CDS <XR_PAGE_TITLE>
J 0
(-8315 5200);
DISPLAY 0.638298 (-8315 5200);
PAINT PINK (-8315 5200);
DISPLAY INVISIBLE (-8315 5200);
FORCEPROP 1 LAST SCH_TITLE SKYLAKE - SKT0 - 16 OF 21
J 0
(-8375 0);
DISPLAY 1.212766 (-8375 0);
PAINT GREEN (-8375 0);
FORCEPROP 2 LAST PAGE_BORDER TRUE
J 0
(-8315 5200);
DISPLAY 0.851064 (-8315 5200);
PAINT PINK (-8315 5200);
DISPLAY INVISIBLE (-8315 5200);
FORCEPROP 2 LAST CDS_LIB mstr_symbols
J 0
(-425 -50);
PAINT ORANGE (-425 -50);
DISPLAY INVISIBLE (-425 -50);
FORCEPROP 1 LAST COMMENT_BODY TRUE
J 0
(-413 -38);
DISPLAY 0.638298 (-413 -38);
PAINT GREEN (-413 -38);
DISPLAY INVISIBLE (-413 -38);
FORCEPROP 2 LAST CDS_XR_PAGE_TITLE CR-36 : @BASEBOARD_FAB2_LIB.BASEBOARD_FAB2(SCH_1):PAGE36
J 0
(-8315 5200);
DISPLAY 0.638298 (-8315 5200);
PAINT PINK (-8315 5200);
DISPLAY INVISIBLE (-8315 5200);
FORCEADD DESIGN_NOTE..1
(-6475 1125);
FORCEPROP 0 LAST L1 CPU SYMBOLS 1-30 ARE PRELIMINARY AND SUBJECT TO CHANGE
J 0
(-6675 1000);
DISPLAY 1.021277 (-6675 1000);
PAINT ORANGE (-6675 1000);
FORCEPROP 2 LAST CDS_LIB mstr_symbols
J 0
(-6475 1125);
PAINT ORANGE (-6475 1125);
DISPLAY INVISIBLE (-6475 1125);
FORCEPROP 1 LAST COMMENT_BODY TRUE
J 0
(-6450 1225);
DISPLAY 0.978723 (-6450 1225);
PAINT ORANGE (-6450 1225);
DISPLAY INVISIBLE (-6450 1225);
FORCEADD DESIGN_NOTE..1
(-8025 3925);
FORCEPROP 0 LAST L1 MCP CLK IS USED FOR DEBUG ONLY
J 0
(-8200 3800);
DISPLAY 1.021277 (-8200 3800);
PAINT ORANGE (-8200 3800);
FORCEPROP 2 LAST CDS_LIB mstr_symbols
J 0
(-8025 3925);
PAINT ORANGE (-8025 3925);
DISPLAY INVISIBLE (-8025 3925);
FORCEPROP 1 LAST COMMENT_BODY TRUE
J 0
(-8000 4025);
DISPLAY 0.978723 (-8000 4025);
PAINT ORANGE (-8000 4025);
DISPLAY INVISIBLE (-8000 4025);
WIRE 16 -1 (-4500 3650)(-4500 3750);
WIRE 16 -1 (-4500 3600)(-4500 3650);
WIRE 16 -1 (-5475 3650)(-4500 3650);
WIRE 16 -1 (-4500 3450)(-4500 3600);
WIRE 16 -1 (-5475 3600)(-4500 3600);
WIRE 16 -1 (-4500 3350)(-4500 3450);
WIRE 16 -1 (-5475 3450)(-4500 3450);
WIRE 16 -1 (-4500 3250)(-4500 3350);
WIRE 16 -1 (-5475 3350)(-4500 3350);
WIRE 16 -1 (-4500 3150)(-4500 3250);
WIRE 16 -1 (-5475 3250)(-4500 3250);
WIRE 16 -1 (-4500 3100)(-4500 3150);
WIRE 16 -1 (-5475 3150)(-4500 3150);
WIRE 16 -1 (-4500 2950)(-4500 3100);
WIRE 16 -1 (-5475 3100)(-4500 3100);
WIRE 16 -1 (-4500 2850)(-4500 2950);
WIRE 16 -1 (-5475 2950)(-4500 2950);
WIRE 16 -1 (-4500 2800)(-4500 2850);
WIRE 16 -1 (-5475 2850)(-4500 2850);
WIRE 16 -1 (-4500 2700)(-4500 2800);
WIRE 16 -1 (-5475 2800)(-4500 2800);
WIRE 16 -1 (-4500 2550)(-4500 2700);
WIRE 16 -1 (-5475 2700)(-4500 2700);
WIRE 16 -1 (-4500 2500)(-4500 2550);
WIRE 16 -1 (-5475 2550)(-4500 2550);
WIRE 16 -1 (-4500 2450)(-4500 2500);
WIRE 16 -1 (-5475 2500)(-4500 2500);
WIRE 16 -1 (-4500 2250)(-4500 2450);
WIRE 16 -1 (-5475 2450)(-4500 2450);
WIRE 16 -1 (-4500 2150)(-4500 2250);
WIRE 16 -1 (-5475 2250)(-4500 2250);
WIRE 16 -1 (-4500 2000)(-4500 2150);
WIRE 16 -1 (-5475 2150)(-4500 2150);
WIRE 16 -1 (-4500 1950)(-4500 2000);
WIRE 16 -1 (-5475 2000)(-4500 2000);
WIRE 16 -1 (-5475 1950)(-4500 1950);
WIRE 16 -1 (-925 2575)(-925 2650);
WIRE 16 -1 (-1725 2575)(-925 2575);
WIRE 16 -1 (-925 2325)(-925 2575);
WIRE 16 -1 (-925 2175)(-925 2325);
WIRE 16 -1 (-1700 2325)(-925 2325);
WIRE 16 -1 (-1725 2525)(-1725 2575);
WIRE 16 -1 (-1850 2575)(-1725 2575);
WIRE 16 -1 (-1725 2475)(-1725 2525);
WIRE 16 -1 (-1850 2525)(-1725 2525);
WIRE 16 -1 (-1700 2275)(-1700 2325);
WIRE 16 -1 (-1850 2325)(-1700 2325);
WIRE 16 -1 (-1850 2175)(-925 2175);
WIRE 16 -1 (-1850 2275)(-1700 2275);
WIRE 16 -1 (-1725 2425)(-1725 2475);
WIRE 16 -1 (-1850 2475)(-1725 2475);
WIRE 16 -1 (-1850 2425)(-1725 2425);
WIRE 16 -1 (-7850 2250)(-7850 2300);
WIRE 16 -1 (-7350 2250)(-7850 2250);
WIRE 16 -1 (-7350 2200)(-7350 2250);
WIRE 16 -1 (-6675 2250)(-7350 2250);
WIRE 16 -1 (-7350 2150)(-7350 2200);
WIRE 16 -1 (-6675 2200)(-7350 2200);
WIRE 16 -1 (-7350 2100)(-7350 2150);
WIRE 16 -1 (-6675 2150)(-7350 2150);
WIRE 16 -1 (-7350 2050)(-7350 2100);
WIRE 16 -1 (-6675 2100)(-7350 2100);
WIRE 16 -1 (-7350 2050)(-7350 1950);
WIRE 16 -1 (-6675 2050)(-7350 2050);
WIRE 16 -1 (-7350 1950)(-7350 1850);
WIRE 16 -1 (-6675 1950)(-7350 1950);
WIRE 16 -1 (-7350 1700)(-7350 1850);
WIRE 16 -1 (-6675 1850)(-7350 1850);
WIRE 16 -1 (-7350 1650)(-7350 1700);
WIRE 16 -1 (-6675 1700)(-7350 1700);
WIRE 16 -1 (-7350 1600)(-7350 1650);
WIRE 16 -1 (-6675 1650)(-7350 1650);
WIRE 16 -1 (-7350 1600)(-7350 1500);
WIRE 16 -1 (-6675 1600)(-7350 1600);
WIRE 16 -1 (-7350 1450)(-7350 1500);
WIRE 16 -1 (-6675 1500)(-7350 1500);
WIRE 16 -1 (-6675 1450)(-7350 1450);
WIRE 16 -1 (-7850 2000)(-7850 2050);
WIRE 16 -1 (-7600 2000)(-7850 2000);
WIRE 16 -1 (-7600 2000)(-7600 1900);
WIRE 16 -1 (-6675 2000)(-7600 2000);
WIRE 16 -1 (-7600 1800)(-7600 1900);
WIRE 16 -1 (-6675 1900)(-7600 1900);
WIRE 16 -1 (-7600 1750)(-7600 1800);
WIRE 16 -1 (-6675 1800)(-7600 1800);
WIRE 16 -1 (-7600 1550)(-7600 1750);
WIRE 16 -1 (-6675 1750)(-7600 1750);
WIRE 16 -1 (-6675 1550)(-7600 1550);
WIRE 16 -1 (-7350 2300)(-6675 2300);
FORCEPROP 2 LAST SIG_NAME TP_CPU0_RSVD_144
J 0
(-7342 2309);
DISPLAY 0.617021 (-7342 2309);
PAINT ORANGE (-7342 2309);
FORCEPROP 2 LASTPROP $XRERR UNIQUE?
J 0
(-7590 2300);
DISPLAY 0.638298 (-7590 2300);
PAINT MONO (-7590 2300);
DISPLAY INVISIBLE (-7590 2300);
WIRE 16 -1 (-7350 2600)(-6675 2600);
FORCEPROP 2 LAST SIG_NAME TP_CPU0_RSVD_150
J 0
(-7342 2609);
DISPLAY 0.617021 (-7342 2609);
PAINT ORANGE (-7342 2609);
FORCEPROP 2 LASTPROP $XRERR UNIQUE?
J 0
(-7590 2600);
DISPLAY 0.638298 (-7590 2600);
PAINT MONO (-7590 2600);
DISPLAY INVISIBLE (-7590 2600);
WIRE 16 -1 (-7550 2750)(-6675 2750);
FORCEPROP 2 LAST SIG_NAME CLK_100M_CPU0_RC_REFCLK1_DP
J 0
(-7492 2759);
DISPLAY 0.617021 (-7492 2759);
PAINT ORANGE (-7492 2759);
WIRE 16 -1 (-7350 2800)(-6675 2800);
FORCEPROP 2 LAST SIG_NAME TP_CPU0_RSVD_154
J 0
(-7342 2809);
DISPLAY 0.617021 (-7342 2809);
PAINT ORANGE (-7342 2809);
FORCEPROP 2 LASTPROP $XRERR UNIQUE?
J 0
(-7590 2800);
DISPLAY 0.638298 (-7590 2800);
PAINT MONO (-7590 2800);
DISPLAY INVISIBLE (-7590 2800);
WIRE 16 -1 (-7350 2550)(-6675 2550);
FORCEPROP 2 LAST SIG_NAME TP_CPU0_RSVD_149
J 0
(-7342 2559);
DISPLAY 0.617021 (-7342 2559);
PAINT ORANGE (-7342 2559);
FORCEPROP 2 LASTPROP $XRERR UNIQUE?
J 0
(-7590 2550);
DISPLAY 0.638298 (-7590 2550);
PAINT MONO (-7590 2550);
DISPLAY INVISIBLE (-7590 2550);
WIRE 16 -1 (-7350 2500)(-6675 2500);
FORCEPROP 2 LAST SIG_NAME TP_CPU0_RSVD_148
J 0
(-7342 2509);
DISPLAY 0.617021 (-7342 2509);
PAINT ORANGE (-7342 2509);
FORCEPROP 2 LASTPROP $XRERR UNIQUE?
J 0
(-7590 2500);
DISPLAY 0.638298 (-7590 2500);
PAINT MONO (-7590 2500);
DISPLAY INVISIBLE (-7590 2500);
WIRE 16 -1 (-7350 2450)(-6675 2450);
FORCEPROP 2 LAST SIG_NAME TP_CPU0_RSVD_147
J 0
(-7342 2459);
DISPLAY 0.617021 (-7342 2459);
PAINT ORANGE (-7342 2459);
FORCEPROP 2 LASTPROP $XRERR UNIQUE?
J 0
(-7590 2450);
DISPLAY 0.638298 (-7590 2450);
PAINT MONO (-7590 2450);
DISPLAY INVISIBLE (-7590 2450);
WIRE 16 -1 (-7350 2400)(-6675 2400);
FORCEPROP 2 LAST SIG_NAME TP_CPU0_RSVD_146
J 0
(-7342 2409);
DISPLAY 0.617021 (-7342 2409);
PAINT ORANGE (-7342 2409);
FORCEPROP 2 LASTPROP $XRERR UNIQUE?
J 0
(-7590 2400);
DISPLAY 0.638298 (-7590 2400);
PAINT MONO (-7590 2400);
DISPLAY INVISIBLE (-7590 2400);
WIRE 16 -1 (-7350 2350)(-6675 2350);
FORCEPROP 2 LAST SIG_NAME TP_CPU0_RSVD_145
J 0
(-7342 2359);
DISPLAY 0.617021 (-7342 2359);
PAINT ORANGE (-7342 2359);
FORCEPROP 2 LASTPROP $XRERR UNIQUE?
J 0
(-7590 2350);
DISPLAY 0.638298 (-7590 2350);
PAINT MONO (-7590 2350);
DISPLAY INVISIBLE (-7590 2350);
WIRE 16 -1 (-7350 2700)(-6675 2700);
FORCEPROP 2 LAST SIG_NAME TP_CPU0_RSVD_152
J 0
(-7342 2709);
DISPLAY 0.617021 (-7342 2709);
PAINT ORANGE (-7342 2709);
FORCEPROP 2 LASTPROP $XRERR UNIQUE?
J 0
(-7590 2700);
DISPLAY 0.638298 (-7590 2700);
PAINT MONO (-7590 2700);
DISPLAY INVISIBLE (-7590 2700);
WIRE 16 -1 (-7350 2650)(-6675 2650);
FORCEPROP 2 LAST SIG_NAME TP_CPU0_RSVD_151
J 0
(-7342 2659);
DISPLAY 0.617021 (-7342 2659);
PAINT ORANGE (-7342 2659);
FORCEPROP 2 LASTPROP $XRERR UNIQUE?
J 0
(-7590 2650);
DISPLAY 0.638298 (-7590 2650);
PAINT MONO (-7590 2650);
DISPLAY INVISIBLE (-7590 2650);
WIRE 16 -1 (-4800 3550)(-5475 3550);
FORCEPROP 2 LAST SIG_NAME TP_CPU0_RSVD_124
J 0
(-5342 3559);
DISPLAY 0.617021 (-5342 3559);
PAINT ORANGE (-5342 3559);
FORCEPROP 2 LASTPROP $XRERR UNIQUE?
J 0
(-4770 3550);
DISPLAY 0.638298 (-4770 3550);
PAINT MONO (-4770 3550);
DISPLAY INVISIBLE (-4770 3550);
WIRE 16 -1 (-1175 2225)(-1850 2225);
FORCEPROP 2 LAST SIG_NAME TP_CPU0_RSVD_82
J 0
(-1700 2235);
DISPLAY 0.617021 (-1700 2235);
PAINT ORANGE (-1700 2235);
FORCEPROP 2 LASTPROP $XRERR UNIQUE?
J 0
(-1145 2225);
DISPLAY 0.638298 (-1145 2225);
PAINT MONO (-1145 2225);
DISPLAY INVISIBLE (-1145 2225);
WIRE 16 -1 (-4800 3000)(-5475 3000);
FORCEPROP 2 LAST SIG_NAME TP_CPU0_RSVD_113
J 0
(-5342 3009);
DISPLAY 0.617021 (-5342 3009);
PAINT ORANGE (-5342 3009);
FORCEPROP 2 LASTPROP $XRERR UNIQUE?
J 0
(-4770 3000);
DISPLAY 0.638298 (-4770 3000);
PAINT MONO (-4770 3000);
DISPLAY INVISIBLE (-4770 3000);
WIRE 16 -1 (-7350 2850)(-6675 2850);
FORCEPROP 2 LAST SIG_NAME TP_CPU0_RSVD_155
J 0
(-7342 2859);
DISPLAY 0.617021 (-7342 2859);
PAINT ORANGE (-7342 2859);
FORCEPROP 2 LASTPROP $XRERR UNIQUE?
J 0
(-7590 2850);
DISPLAY 0.638298 (-7590 2850);
PAINT MONO (-7590 2850);
DISPLAY INVISIBLE (-7590 2850);
WIRE 16 -1 (-7350 2900)(-6675 2900);
FORCEPROP 2 LAST SIG_NAME TP_CPU0_RSVD_156
J 0
(-7342 2909);
DISPLAY 0.617021 (-7342 2909);
PAINT ORANGE (-7342 2909);
FORCEPROP 2 LASTPROP $XRERR UNIQUE?
J 0
(-7590 2900);
DISPLAY 0.638298 (-7590 2900);
PAINT MONO (-7590 2900);
DISPLAY INVISIBLE (-7590 2900);
WIRE 16 -1 (-7350 2950)(-6675 2950);
FORCEPROP 2 LAST SIG_NAME TP_CPU0_RSVD_157
J 0
(-7342 2959);
DISPLAY 0.617021 (-7342 2959);
PAINT ORANGE (-7342 2959);
FORCEPROP 2 LASTPROP $XRERR UNIQUE?
J 0
(-7590 2950);
DISPLAY 0.638298 (-7590 2950);
PAINT MONO (-7590 2950);
DISPLAY INVISIBLE (-7590 2950);
WIRE 16 -1 (-7350 3000)(-6675 3000);
FORCEPROP 2 LAST SIG_NAME TP_CPU0_RSVD_158
J 0
(-7342 3009);
DISPLAY 0.617021 (-7342 3009);
PAINT ORANGE (-7342 3009);
FORCEPROP 2 LASTPROP $XRERR UNIQUE?
J 0
(-7590 3000);
DISPLAY 0.638298 (-7590 3000);
PAINT MONO (-7590 3000);
DISPLAY INVISIBLE (-7590 3000);
WIRE 16 -1 (-7350 3050)(-6675 3050);
FORCEPROP 2 LAST SIG_NAME TP_CPU0_RSVD_159
J 0
(-7342 3059);
DISPLAY 0.617021 (-7342 3059);
PAINT ORANGE (-7342 3059);
FORCEPROP 2 LASTPROP $XRERR UNIQUE?
J 0
(-7590 3050);
DISPLAY 0.638298 (-7590 3050);
PAINT MONO (-7590 3050);
DISPLAY INVISIBLE (-7590 3050);
WIRE 16 -1 (-7350 3100)(-6675 3100);
FORCEPROP 2 LAST SIG_NAME TP_CPU0_RSVD_160
J 0
(-7342 3109);
DISPLAY 0.617021 (-7342 3109);
PAINT ORANGE (-7342 3109);
FORCEPROP 2 LASTPROP $XRERR UNIQUE?
J 0
(-7590 3100);
DISPLAY 0.638298 (-7590 3100);
PAINT MONO (-7590 3100);
DISPLAY INVISIBLE (-7590 3100);
WIRE 16 -1 (-7350 3150)(-6675 3150);
FORCEPROP 2 LAST SIG_NAME TP_CPU0_RSVD_161
J 0
(-7342 3159);
DISPLAY 0.617021 (-7342 3159);
PAINT ORANGE (-7342 3159);
FORCEPROP 2 LASTPROP $XRERR UNIQUE?
J 0
(-7590 3150);
DISPLAY 0.638298 (-7590 3150);
PAINT MONO (-7590 3150);
DISPLAY INVISIBLE (-7590 3150);
WIRE 16 -1 (-7350 3200)(-6675 3200);
FORCEPROP 2 LAST SIG_NAME TP_CPU0_RSVD_162
J 0
(-7342 3209);
DISPLAY 0.617021 (-7342 3209);
PAINT ORANGE (-7342 3209);
FORCEPROP 2 LASTPROP $XRERR UNIQUE?
J 0
(-7590 3200);
DISPLAY 0.638298 (-7590 3200);
PAINT MONO (-7590 3200);
DISPLAY INVISIBLE (-7590 3200);
WIRE 16 -1 (-7350 3250)(-6675 3250);
FORCEPROP 2 LAST SIG_NAME TP_CPU0_RSVD_163
J 0
(-7342 3259);
DISPLAY 0.617021 (-7342 3259);
PAINT ORANGE (-7342 3259);
FORCEPROP 2 LASTPROP $XRERR UNIQUE?
J 0
(-7590 3250);
DISPLAY 0.638298 (-7590 3250);
PAINT MONO (-7590 3250);
DISPLAY INVISIBLE (-7590 3250);
WIRE 16 -1 (-7350 3300)(-6675 3300);
FORCEPROP 2 LAST SIG_NAME TP_CPU0_RSVD_164
J 0
(-7342 3309);
DISPLAY 0.617021 (-7342 3309);
PAINT ORANGE (-7342 3309);
FORCEPROP 2 LASTPROP $XRERR UNIQUE?
J 0
(-7590 3300);
DISPLAY 0.638298 (-7590 3300);
PAINT MONO (-7590 3300);
DISPLAY INVISIBLE (-7590 3300);
WIRE 16 -1 (-7350 3400)(-6675 3400);
FORCEPROP 2 LAST SIG_NAME TP_CPU0_RSVD_166
J 0
(-7342 3409);
DISPLAY 0.617021 (-7342 3409);
PAINT ORANGE (-7342 3409);
FORCEPROP 2 LASTPROP $XRERR UNIQUE?
J 0
(-7590 3400);
DISPLAY 0.638298 (-7590 3400);
PAINT MONO (-7590 3400);
DISPLAY INVISIBLE (-7590 3400);
WIRE 16 -1 (-7350 3450)(-6675 3450);
FORCEPROP 2 LAST SIG_NAME TP_CPU0_RSVD_167
J 0
(-7342 3459);
DISPLAY 0.617021 (-7342 3459);
PAINT ORANGE (-7342 3459);
FORCEPROP 2 LASTPROP $XRERR UNIQUE?
J 0
(-7590 3450);
DISPLAY 0.638298 (-7590 3450);
PAINT MONO (-7590 3450);
DISPLAY INVISIBLE (-7590 3450);
WIRE 16 -1 (-7350 3500)(-6675 3500);
FORCEPROP 2 LAST SIG_NAME TP_CPU0_RSVD_168
J 0
(-7342 3509);
DISPLAY 0.617021 (-7342 3509);
PAINT ORANGE (-7342 3509);
FORCEPROP 2 LASTPROP $XRERR UNIQUE?
J 0
(-7590 3500);
DISPLAY 0.638298 (-7590 3500);
PAINT MONO (-7590 3500);
DISPLAY INVISIBLE (-7590 3500);
WIRE 16 -1 (-7350 3550)(-6675 3550);
FORCEPROP 2 LAST SIG_NAME TP_CPU0_RSVD_169
J 0
(-7342 3559);
DISPLAY 0.617021 (-7342 3559);
PAINT ORANGE (-7342 3559);
FORCEPROP 2 LASTPROP $XRERR UNIQUE?
J 0
(-7590 3550);
DISPLAY 0.638298 (-7590 3550);
PAINT MONO (-7590 3550);
DISPLAY INVISIBLE (-7590 3550);
WIRE 16 -1 (-7350 3600)(-6675 3600);
FORCEPROP 2 LAST SIG_NAME TP_CPU0_RSVD_170
J 0
(-7342 3609);
DISPLAY 0.617021 (-7342 3609);
PAINT ORANGE (-7342 3609);
FORCEPROP 2 LASTPROP $XRERR UNIQUE?
J 0
(-7590 3600);
DISPLAY 0.638298 (-7590 3600);
PAINT MONO (-7590 3600);
DISPLAY INVISIBLE (-7590 3600);
WIRE 16 -1 (-7350 3650)(-6675 3650);
FORCEPROP 2 LAST SIG_NAME TP_CPU0_RSVD_171
J 0
(-7342 3659);
DISPLAY 0.617021 (-7342 3659);
PAINT ORANGE (-7342 3659);
FORCEPROP 2 LASTPROP $XRERR UNIQUE?
J 0
(-7590 3650);
DISPLAY 0.638298 (-7590 3650);
PAINT MONO (-7590 3650);
DISPLAY INVISIBLE (-7590 3650);
WIRE 16 -1 (-7550 3350)(-6675 3350);
FORCEPROP 2 LAST SIG_NAME CLK_100M_CPU0_RC_REFCLK1_DN
J 0
(-7517 3359);
DISPLAY 0.617021 (-7517 3359);
PAINT ORANGE (-7517 3359);
WIRE 16 -1 (-4800 1900)(-5475 1900);
FORCEPROP 2 LAST SIG_NAME TP_CPU0_RSVD_255
J 0
(-5342 1909);
DISPLAY 0.617021 (-5342 1909);
PAINT ORANGE (-5342 1909);
FORCEPROP 2 LASTPROP $XRERR UNIQUE?
J 0
(-4770 1900);
DISPLAY 0.638298 (-4770 1900);
PAINT MONO (-4770 1900);
DISPLAY INVISIBLE (-4770 1900);
WIRE 16 -1 (-5475 2050)(-4800 2050);
FORCEPROP 2 LAST SIG_NAME TP_CPU0_RSVD_94
J 0
(-5342 2059);
DISPLAY 0.617021 (-5342 2059);
PAINT ORANGE (-5342 2059);
FORCEPROP 2 LASTPROP $XRERR UNIQUE?
J 0
(-4770 2050);
DISPLAY 0.638298 (-4770 2050);
PAINT MONO (-4770 2050);
DISPLAY INVISIBLE (-4770 2050);
WIRE 16 -1 (-4800 2100)(-5475 2100);
FORCEPROP 2 LAST SIG_NAME TP_CPU0_RSVD_95
J 0
(-5342 2109);
DISPLAY 0.617021 (-5342 2109);
PAINT ORANGE (-5342 2109);
FORCEPROP 2 LASTPROP $XRERR UNIQUE?
J 0
(-4770 2100);
DISPLAY 0.638298 (-4770 2100);
PAINT MONO (-4770 2100);
DISPLAY INVISIBLE (-4770 2100);
WIRE 16 -1 (-4800 2200)(-5475 2200);
FORCEPROP 2 LAST SIG_NAME TP_CPU0_RSVD_97
J 0
(-5342 2209);
DISPLAY 0.617021 (-5342 2209);
PAINT ORANGE (-5342 2209);
FORCEPROP 2 LASTPROP $XRERR UNIQUE?
J 0
(-4770 2200);
DISPLAY 0.638298 (-4770 2200);
PAINT MONO (-4770 2200);
DISPLAY INVISIBLE (-4770 2200);
WIRE 16 -1 (-4800 2300)(-5475 2300);
FORCEPROP 2 LAST SIG_NAME TP_CPU0_RSVD_99
J 0
(-5342 2309);
DISPLAY 0.617021 (-5342 2309);
PAINT ORANGE (-5342 2309);
FORCEPROP 2 LASTPROP $XRERR UNIQUE?
J 0
(-4770 2300);
DISPLAY 0.638298 (-4770 2300);
PAINT MONO (-4770 2300);
DISPLAY INVISIBLE (-4770 2300);
WIRE 16 -1 (-4800 2350)(-5475 2350);
FORCEPROP 2 LAST SIG_NAME TP_CPU0_RSVD_100
J 0
(-5342 2359);
DISPLAY 0.617021 (-5342 2359);
PAINT ORANGE (-5342 2359);
FORCEPROP 2 LASTPROP $XRERR UNIQUE?
J 0
(-4770 2350);
DISPLAY 0.638298 (-4770 2350);
PAINT MONO (-4770 2350);
DISPLAY INVISIBLE (-4770 2350);
WIRE 16 -1 (-4800 2400)(-5475 2400);
FORCEPROP 2 LAST SIG_NAME TP_CPU0_RSVD_101
J 0
(-5342 2409);
DISPLAY 0.617021 (-5342 2409);
PAINT ORANGE (-5342 2409);
FORCEPROP 2 LASTPROP $XRERR UNIQUE?
J 0
(-4770 2400);
DISPLAY 0.638298 (-4770 2400);
PAINT MONO (-4770 2400);
DISPLAY INVISIBLE (-4770 2400);
WIRE 16 -1 (-4800 2600)(-5475 2600);
FORCEPROP 2 LAST SIG_NAME TP_CPU0_RSVD_105
J 0
(-5342 2609);
DISPLAY 0.617021 (-5342 2609);
PAINT ORANGE (-5342 2609);
FORCEPROP 2 LASTPROP $XRERR UNIQUE?
J 0
(-4770 2600);
DISPLAY 0.638298 (-4770 2600);
PAINT MONO (-4770 2600);
DISPLAY INVISIBLE (-4770 2600);
WIRE 16 -1 (-4800 2650)(-5475 2650);
FORCEPROP 2 LAST SIG_NAME TP_CPU0_RSVD_106
J 0
(-5342 2659);
DISPLAY 0.617021 (-5342 2659);
PAINT ORANGE (-5342 2659);
FORCEPROP 2 LASTPROP $XRERR UNIQUE?
J 0
(-4770 2650);
DISPLAY 0.638298 (-4770 2650);
PAINT MONO (-4770 2650);
DISPLAY INVISIBLE (-4770 2650);
WIRE 16 -1 (-4800 2750)(-5475 2750);
FORCEPROP 2 LAST SIG_NAME TP_CPU0_RSVD_108
J 0
(-5342 2759);
DISPLAY 0.617021 (-5342 2759);
PAINT ORANGE (-5342 2759);
FORCEPROP 2 LASTPROP $XRERR UNIQUE?
J 0
(-4770 2750);
DISPLAY 0.638298 (-4770 2750);
PAINT MONO (-4770 2750);
DISPLAY INVISIBLE (-4770 2750);
WIRE 16 -1 (-4800 2900)(-5475 2900);
FORCEPROP 2 LAST SIG_NAME TP_CPU0_RSVD_111
J 0
(-5342 2909);
DISPLAY 0.617021 (-5342 2909);
PAINT ORANGE (-5342 2909);
FORCEPROP 2 LASTPROP $XRERR UNIQUE?
J 0
(-4770 2900);
DISPLAY 0.638298 (-4770 2900);
PAINT MONO (-4770 2900);
DISPLAY INVISIBLE (-4770 2900);
WIRE 16 -1 (-4800 3050)(-5475 3050);
FORCEPROP 2 LAST SIG_NAME TP_CPU0_RSVD_114
J 0
(-5342 3059);
DISPLAY 0.617021 (-5342 3059);
PAINT ORANGE (-5342 3059);
FORCEPROP 2 LASTPROP $XRERR UNIQUE?
J 0
(-4770 3050);
DISPLAY 0.638298 (-4770 3050);
PAINT MONO (-4770 3050);
DISPLAY INVISIBLE (-4770 3050);
WIRE 16 -1 (-4800 3200)(-5475 3200);
FORCEPROP 2 LAST SIG_NAME TP_CPU0_RSVD_117
J 0
(-5342 3209);
DISPLAY 0.617021 (-5342 3209);
PAINT ORANGE (-5342 3209);
FORCEPROP 2 LASTPROP $XRERR UNIQUE?
J 0
(-4770 3200);
DISPLAY 0.638298 (-4770 3200);
PAINT MONO (-4770 3200);
DISPLAY INVISIBLE (-4770 3200);
WIRE 16 -1 (-5475 3300)(-4800 3300);
FORCEPROP 2 LAST SIG_NAME TP_CPU0_RSVD_119
J 0
(-5342 3309);
DISPLAY 0.617021 (-5342 3309);
PAINT ORANGE (-5342 3309);
FORCEPROP 2 LASTPROP $XRERR UNIQUE?
J 0
(-4770 3300);
DISPLAY 0.638298 (-4770 3300);
PAINT MONO (-4770 3300);
DISPLAY INVISIBLE (-4770 3300);
WIRE 16 -1 (-5475 3400)(-4800 3400);
FORCEPROP 2 LAST SIG_NAME TP_CPU0_RSVD_121
J 0
(-5342 3409);
DISPLAY 0.617021 (-5342 3409);
PAINT ORANGE (-5342 3409);
FORCEPROP 2 LASTPROP $XRERR UNIQUE?
J 0
(-4770 3400);
DISPLAY 0.638298 (-4770 3400);
PAINT MONO (-4770 3400);
DISPLAY INVISIBLE (-4770 3400);
WIRE 16 -1 (-4800 3500)(-5475 3500);
FORCEPROP 2 LAST SIG_NAME TP_CPU0_RSVD_123
J 0
(-5342 3509);
DISPLAY 0.617021 (-5342 3509);
PAINT ORANGE (-5342 3509);
FORCEPROP 2 LASTPROP $XRERR UNIQUE?
J 0
(-4770 3500);
DISPLAY 0.638298 (-4770 3500);
PAINT MONO (-4770 3500);
DISPLAY INVISIBLE (-4770 3500);
WIRE 16 -1 (-1175 2875)(-1850 2875);
FORCEPROP 2 LAST SIG_NAME TP_CPU0_TEST_9
J 0
(-1700 2885);
DISPLAY 0.617021 (-1700 2885);
PAINT ORANGE (-1700 2885);
FORCEPROP 2 LASTPROP $XRERR UNIQUE?
J 0
(-1145 2875);
DISPLAY 0.638298 (-1145 2875);
PAINT MONO (-1145 2875);
DISPLAY INVISIBLE (-1145 2875);
WIRE 16 -1 (-1175 2925)(-1850 2925);
FORCEPROP 2 LAST SIG_NAME TP_CPU0_TEST_8
J 0
(-1700 2935);
DISPLAY 0.617021 (-1700 2935);
PAINT ORANGE (-1700 2935);
FORCEPROP 2 LASTPROP $XRERR UNIQUE?
J 0
(-1145 2925);
DISPLAY 0.638298 (-1145 2925);
PAINT MONO (-1145 2925);
DISPLAY INVISIBLE (-1145 2925);
WIRE 16 -1 (-1850 2975)(-1175 2975);
FORCEPROP 2 LAST SIG_NAME TP_CPU0_TEST_7
J 0
(-1700 2985);
DISPLAY 0.617021 (-1700 2985);
PAINT ORANGE (-1700 2985);
FORCEPROP 2 LASTPROP $XRERR UNIQUE?
J 0
(-1145 2975);
DISPLAY 0.638298 (-1145 2975);
PAINT MONO (-1145 2975);
DISPLAY INVISIBLE (-1145 2975);
WIRE 16 -1 (-1175 3025)(-1850 3025);
FORCEPROP 2 LAST SIG_NAME TP_CPU0_TEST_6
J 0
(-1700 3035);
DISPLAY 0.617021 (-1700 3035);
PAINT ORANGE (-1700 3035);
FORCEPROP 2 LASTPROP $XRERR UNIQUE?
J 0
(-1145 3025);
DISPLAY 0.638298 (-1145 3025);
PAINT MONO (-1145 3025);
DISPLAY INVISIBLE (-1145 3025);
WIRE 16 -1 (-1175 2825)(-1850 2825);
FORCEPROP 2 LAST SIG_NAME TP_CPU0_TEST_10
J 0
(-1700 2835);
DISPLAY 0.617021 (-1700 2835);
PAINT ORANGE (-1700 2835);
FORCEPROP 2 LASTPROP $XRERR UNIQUE?
J 0
(-1145 2825);
DISPLAY 0.638298 (-1145 2825);
PAINT MONO (-1145 2825);
DISPLAY INVISIBLE (-1145 2825);
WIRE 16 -1 (-1850 2375)(-1175 2375);
FORCEPROP 2 LAST SIG_NAME TP_CPU0_RSVD_85
J 0
(-1700 2385);
DISPLAY 0.617021 (-1700 2385);
PAINT ORANGE (-1700 2385);
FORCEPROP 2 LASTPROP $XRERR UNIQUE?
J 0
(-1145 2375);
DISPLAY 0.638298 (-1145 2375);
PAINT MONO (-1145 2375);
DISPLAY INVISIBLE (-1145 2375);
WIRE 16 -1 (-1175 2675)(-1850 2675);
FORCEPROP 2 LAST SIG_NAME TP_CPU0_RSVD_90
J 0
(-1700 2685);
DISPLAY 0.617021 (-1700 2685);
PAINT ORANGE (-1700 2685);
FORCEPROP 2 LASTPROP $XRERR UNIQUE?
J 0
(-1145 2675);
DISPLAY 0.638298 (-1145 2675);
PAINT MONO (-1145 2675);
DISPLAY INVISIBLE (-1145 2675);
WIRE 16 -1 (-1175 2725)(-1850 2725);
FORCEPROP 2 LAST SIG_NAME TP_CPU0_RSVD_91
J 0
(-1700 2735);
DISPLAY 0.617021 (-1700 2735);
PAINT ORANGE (-1700 2735);
FORCEPROP 2 LASTPROP $XRERR UNIQUE?
J 0
(-1145 2725);
DISPLAY 0.638298 (-1145 2725);
PAINT MONO (-1145 2725);
DISPLAY INVISIBLE (-1145 2725);
DOT 1 (-4500 3250);
DOT 1 (-4500 2000);
DOT 1 (-4500 2150);
DOT 1 (-4500 2250);
DOT 1 (-4500 2450);
DOT 1 (-4500 2500);
DOT 1 (-4500 2550);
DOT 1 (-4500 2700);
DOT 1 (-4500 2800);
DOT 1 (-4500 2850);
DOT 1 (-4500 2950);
DOT 1 (-4500 3100);
DOT 1 (-4500 3150);
DOT 1 (-4500 3350);
DOT 1 (-4500 3450);
DOT 1 (-4500 3600);
DOT 1 (-4500 3650);
DOT 1 (-925 2325);
DOT 1 (-925 2575);
DOT 1 (-1700 2325);
DOT 1 (-1725 2475);
DOT 1 (-1725 2525);
DOT 1 (-1725 2575);
DOT 1 (-7350 2250);
DOT 1 (-7350 2100);
DOT 1 (-7350 2200);
DOT 1 (-7350 1700);
DOT 1 (-7350 1650);
DOT 1 (-7350 1500);
DOT 1 (-7350 1950);
DOT 1 (-7350 2150);
DOT 1 (-7350 2050);
DOT 1 (-7600 2000);
DOT 1 (-7350 1850);
DOT 1 (-7600 1900);
DOT 1 (-7600 1800);
DOT 1 (-7350 1600);
DOT 1 (-7600 1750);
FORCENOTE
SKYLAKE - SKT0 - 16 OF 21
(-2125 100) 0;
DISPLAY LEFT (-2125 100);
DISPLAY 1.021277 (-2125 100);
PAINT RED (-2125 100);
FORCENOTE
BOM_COST=PROC_SOCKET
(-8300 250) 0;
DISPLAY LEFT (-8300 250);
DISPLAY 1.723404 (-8300 250);
PAINT PURPLE (-8300 250);
FORCENOTE
ROOM=CPU0
(-8275 375) 0;
DISPLAY LEFT (-8275 375);
DISPLAY 1.723404 (-8275 375);
PAINT PURPLE (-8275 375);
QUIT
